(kicad_pcb
	(version 20260206)
	(generator "pcbnew")
	(generator_version "10.0")
	(general
		(thickness 1.6)
		(legacy_teardrops no)
	)
	(paper "A4")
	(title_block
		(title "Wiwynn_Tioga_Pass_MB.brd")
		(comment 1 "Tioga Pass / footprints 3530-3536 of 4770")
	)
	(layers
		(0 "F.Cu" signal "TOP")
		(4 "In1.Cu" signal "L2GND")
		(6 "In2.Cu" signal "L3")
		(8 "In3.Cu" signal "L4GND")
		(10 "In4.Cu" signal "L5")
		(12 "In5.Cu" signal "L6GND")
		(14 "In6.Cu" signal "L7VCC")
		(16 "In7.Cu" signal "L8VCC")
		(18 "In8.Cu" signal "L9GND")
		(20 "In9.Cu" signal "L10")
		(22 "In10.Cu" signal "L11GND")
		(24 "In11.Cu" signal "L12")
		(26 "In12.Cu" signal "L13GND")
		(2 "B.Cu" signal "BOTTOM")
		(9 "F.Adhes" user "F.Adhesive")
		(11 "B.Adhes" user "B.Adhesive")
		(13 "F.Paste" user "Package Geometry/Pastemask Top")
		(15 "B.Paste" user "Package Geometry/Pastemask Bottom")
		(5 "F.SilkS" user "Ref Des/Silkscreen Top")
		(7 "B.SilkS" user "Ref Des/Silkscreen Bottom")
		(1 "F.Mask" user "Board Geometry/Soldermask Top")
		(3 "B.Mask" user "Board Geometry/Soldermask Bottom")
		(17 "Dwgs.User" user "User.Drawings")
		(19 "Cmts.User" user "User.Comments")
		(21 "Eco1.User" user "User.Eco1")
		(23 "Eco2.User" user "User.Eco2")
		(25 "Edge.Cuts" user "Board Geometry/Outline")
		(27 "Margin" user)
		(31 "F.CrtYd" user "Package Geometry/Place Bound Top")
		(29 "B.CrtYd" user "Package Geometry/Place Bound Bottom")
		(35 "F.Fab" user "Ref Des/Assembly Top")
		(33 "B.Fab" user "Ref Des/Assembly Bottom")
	)
	(footprint ""
		(layer "B.Cu")
		(at 352.96729 -77.915516 180)
		(property "Reference" "C3P30"
			(at 0 0 0)
			(layer "B.SilkS")
			(hide yes)
			(effects
				(font
					(size 1.27 1.27)
				)
				(justify mirror)
			)
		)
		(property "Value" ""
			(at 0 0 0)
			(layer "B.Fab")
			(effects
				(font
					(size 1.27 1.27)
				)
				(justify mirror)
			)
		)
		(duplicate_pad_numbers_are_jumpers no)
		(fp_poly
			(pts
				(xy -0.3048 -0.1016) (xy -0.3048 0.9906) (xy 0.3048 0.9906) (xy 0.3048 -0.1016)
			)
			(stroke
				(width 0)
				(type default)
			)
			(fill no)
			(layer "B.CrtYd")
		)
		(fp_line
			(start 0.3048 0.9906)
			(end -0.3048 0.9906)
			(stroke
				(width 0.1)
				(type default)
			)
			(layer "B.Fab")
		)
		(fp_line
			(start 0.3048 -0.1016)
			(end 0.3048 0.9906)
			(stroke
				(width 0.1)
				(type default)
			)
			(layer "B.Fab")
		)
		(fp_line
			(start -0.3048 0.9906)
			(end -0.3048 -0.1016)
			(stroke
				(width 0.1)
				(type default)
			)
			(layer "B.Fab")
		)
		(fp_line
			(start -0.3048 -0.1016)
			(end 0.3048 -0.1016)
			(stroke
				(width 0.1)
				(type default)
			)
			(layer "B.Fab")
		)
		(pad "1" smd rect
			(at 0 0)
			(size 0.508 0.508)
			(layers "B.Cu" "B.Mask" "B.Paste")
			(net "P3E_CPU0_PE1_SS_TXP<5>")
		)
		(pad "2" smd rect
			(at 0 0.889)
			(size 0.508 0.508)
			(layers "B.Cu" "B.Mask" "B.Paste")
			(net "P3E_CPU0_PE1_PCH_TXP<5>")
		)
		(zone
			(layer "B.Cu")
			(hatch none 0.5)
			(connect_pads
				(clearance 0)
			)
			(min_thickness 0.25)
			(keepout
				(tracks not_allowed)
				(vias allowed)
				(pads allowed)
				(copperpour not_allowed)
				(footprints allowed)
			)
			(placement
				(enabled no)
				(sheetname "")
			)
			(fill
				(thermal_gap 0.5)
				(thermal_bridge_width 0.5)
				(island_removal_mode 0)
			)
			(polygon
				(pts
					(xy 352.71329 -78.550516) (xy 353.22129 -78.550516) (xy 353.22129 -78.169516) (xy 352.71329 -78.169516)
				)
			)
		)
		(zone
			(layer "B.Cu")
			(hatch none 0.5)
			(connect_pads
				(clearance 0)
			)
			(min_thickness 0.25)
			(keepout
				(tracks allowed)
				(vias not_allowed)
				(pads allowed)
				(copperpour not_allowed)
				(footprints allowed)
			)
			(placement
				(enabled no)
				(sheetname "")
			)
			(fill
				(thermal_gap 0.5)
				(thermal_bridge_width 0.5)
				(island_removal_mode 0)
			)
			(polygon
				(pts
					(xy 352.71329 -78.169516) (xy 353.22129 -78.169516) (xy 353.22129 -78.550516) (xy 352.71329 -78.550516)
				)
			)
		)
	)
	(footprint ""
		(layer "B.Cu")
		(at 487.7054 -36.3474 90)
		(property "Reference" "R9W34"
			(at 0.8382 -0.67818 90)
			(unlocked yes)
			(layer "B.SilkS")
			(effects
				(font
					(size 0.4064 0.254)
					(thickness 0.1524)
				)
				(justify left mirror)
			)
		)
		(property "Value" ""
			(at 0 0 90)
			(layer "B.Fab")
			(effects
				(font
					(size 1.27 1.27)
				)
				(justify mirror)
			)
		)
		(duplicate_pad_numbers_are_jumpers no)
		(fp_poly
			(pts
				(xy 0.2794 -0.1016) (xy -0.2794 -0.1016) (xy -0.2794 0.9906) (xy 0.2794 0.9906)
			)
			(stroke
				(width 0)
				(type default)
			)
			(fill no)
			(layer "B.CrtYd")
		)
		(fp_line
			(start 0.2794 -0.1016)
			(end 0.2794 0.9906)
			(stroke
				(width 0.1)
				(type default)
			)
			(layer "B.Fab")
		)
		(fp_line
			(start -0.2794 -0.1016)
			(end 0.2794 -0.1016)
			(stroke
				(width 0.1)
				(type default)
			)
			(layer "B.Fab")
		)
		(fp_line
			(start 0.2794 0.9906)
			(end -0.2794 0.9906)
			(stroke
				(width 0.1)
				(type default)
			)
			(layer "B.Fab")
		)
		(fp_line
			(start -0.2794 0.9906)
			(end -0.2794 -0.1016)
			(stroke
				(width 0.1)
				(type default)
			)
			(layer "B.Fab")
		)
		(pad "1" smd rect
			(at 0 0 270)
			(size 0.508 0.508)
			(layers "B.Cu" "B.Mask" "B.Paste")
			(net "P3V3_STBY")
		)
		(pad "2" smd rect
			(at 0 0.889 270)
			(size 0.508 0.508)
			(layers "B.Cu" "B.Mask" "B.Paste")
			(net "UART_BMC_RXD5")
		)
		(zone
			(layer "B.Cu")
			(hatch none 0.5)
			(connect_pads
				(clearance 0)
			)
			(min_thickness 0.25)
			(keepout
				(tracks allowed)
				(vias not_allowed)
				(pads allowed)
				(copperpour not_allowed)
				(footprints allowed)
			)
			(placement
				(enabled no)
				(sheetname "")
			)
			(fill
				(thermal_gap 0.5)
				(thermal_bridge_width 0.5)
				(island_removal_mode 0)
			)
			(polygon
				(pts
					(xy 487.9594 -36.6014) (xy 487.9594 -36.0934) (xy 488.3404 -36.0934) (xy 488.3404 -36.6014)
				)
			)
		)
		(zone
			(layer "B.Cu")
			(hatch none 0.5)
			(connect_pads
				(clearance 0)
			)
			(min_thickness 0.25)
			(keepout
				(tracks not_allowed)
				(vias allowed)
				(pads allowed)
				(copperpour not_allowed)
				(footprints allowed)
			)
			(placement
				(enabled no)
				(sheetname "")
			)
			(fill
				(thermal_gap 0.5)
				(thermal_bridge_width 0.5)
				(island_removal_mode 0)
			)
			(polygon
				(pts
					(xy 488.3404 -36.6014) (xy 488.3404 -36.0934) (xy 487.9594 -36.0934) (xy 487.9594 -36.6014)
				)
			)
		)
	)
	(footprint ""
		(layer "B.Cu")
		(at 355.41966 -135.1915 -90)
		(property "Reference" "R12W6"
			(at 0 0 90)
			(layer "B.SilkS")
			(hide yes)
			(effects
				(font
					(size 1.27 1.27)
				)
				(justify mirror)
			)
		)
		(property "Value" "*"
			(at 0 -8.9535 270)
			(unlocked yes)
			(layer "B.Fab")
			(hide yes)
			(effects
				(font
					(size 1.27 1.016)
					(thickness 0.1524)
				)
				(justify mirror)
			)
		)
		(property "Device Type" "665KR5B-1-GP_SMD-RG3-665KR5B-1A"
			(at 0 -10.6299 270)
			(unlocked yes)
			(layer "B.Fab")
			(hide yes)
			(effects
				(font
					(size 1.27 1.016)
					(thickness 0.1524)
				)
				(justify mirror)
			)
		)
		(duplicate_pad_numbers_are_jumpers no)
		(fp_line
			(start -0.889 1.7018)
			(end -0.889 -0.508)
			(stroke
				(width 0.1524)
				(type default)
			)
			(layer "B.SilkS")
		)
		(fp_line
			(start 0.889 1.7018)
			(end -0.889 1.7018)
			(stroke
				(width 0.1524)
				(type default)
			)
			(layer "B.SilkS")
		)
		(fp_line
			(start 0.889 0.0762)
			(end 0.889 1.7018)
			(stroke
				(width 0.1524)
				(type default)
			)
			(layer "B.SilkS")
		)
		(fp_line
			(start -0.889 -1.7018)
			(end -0.889 -0.381)
			(stroke
				(width 0.1524)
				(type default)
			)
			(layer "B.SilkS")
		)
		(fp_line
			(start -0.889 -1.7018)
			(end 0.889 -1.7018)
			(stroke
				(width 0.1524)
				(type default)
			)
			(layer "B.SilkS")
		)
		(fp_line
			(start 0.889 -1.7018)
			(end 0.889 0.2794)
			(stroke
				(width 0.1524)
				(type default)
			)
			(layer "B.SilkS")
		)
		(fp_poly
			(pts
				(xy -0.9652 -1.778) (xy -0.9652 1.778) (xy 0.9652 1.778) (xy 0.9652 -1.778)
			)
			(stroke
				(width 0)
				(type default)
			)
			(fill no)
			(layer "B.CrtYd")
		)
		(fp_rect
			(start 0.9652 1.778)
			(end -0.9652 -1.778)
			(stroke
				(width 0)
				(type default)
			)
			(fill no)
			(layer "B.Fab")
		)
		(pad "1" smd rect
			(at 0 -0.9652 90)
			(size 1.397 1.143)
			(layers "B.Cu" "B.Mask" "B.Paste")
			(net "P12V_STBY")
		)
		(pad "2" smd rect
			(at 0 0.9652 90)
			(size 1.397 1.143)
			(layers "B.Cu" "B.Mask" "B.Paste")
			(net "VR_PVDDQ_DEF_AIINSEN")
		)
	)
	(footprint ""
		(layer "B.Cu")
		(at 341.1982 -87.4522 90)
		(property "Reference" "R3P11"
			(at 0 0 90)
			(layer "B.SilkS")
			(hide yes)
			(effects
				(font
					(size 1.27 1.27)
				)
				(justify mirror)
			)
		)
		(property "Value" ""
			(at 0 0 90)
			(layer "B.Fab")
			(effects
				(font
					(size 1.27 1.27)
				)
				(justify mirror)
			)
		)
		(duplicate_pad_numbers_are_jumpers no)
		(fp_poly
			(pts
				(xy 0.2794 -0.1016) (xy -0.2794 -0.1016) (xy -0.2794 0.9906) (xy 0.2794 0.9906)
			)
			(stroke
				(width 0)
				(type default)
			)
			(fill no)
			(layer "B.CrtYd")
		)
		(fp_line
			(start 0.2794 -0.1016)
			(end 0.2794 0.9906)
			(stroke
				(width 0.1)
				(type default)
			)
			(layer "B.Fab")
		)
		(fp_line
			(start -0.2794 -0.1016)
			(end 0.2794 -0.1016)
			(stroke
				(width 0.1)
				(type default)
			)
			(layer "B.Fab")
		)
		(fp_line
			(start 0.2794 0.9906)
			(end -0.2794 0.9906)
			(stroke
				(width 0.1)
				(type default)
			)
			(layer "B.Fab")
		)
		(fp_line
			(start -0.2794 0.9906)
			(end -0.2794 -0.1016)
			(stroke
				(width 0.1)
				(type default)
			)
			(layer "B.Fab")
		)
		(pad "1" smd rect
			(at 0 0 270)
			(size 0.508 0.508)
			(layers "B.Cu" "B.Mask" "B.Paste")
			(net "SVID_DIO0_CPU0_R")
		)
		(pad "2" smd rect
			(at 0 0.889 270)
			(size 0.508 0.508)
			(layers "B.Cu" "B.Mask" "B.Paste")
			(net "SVID_VDIO_PVCCIO_CPU0")
		)
		(zone
			(layer "B.Cu")
			(hatch none 0.5)
			(connect_pads
				(clearance 0)
			)
			(min_thickness 0.25)
			(keepout
				(tracks allowed)
				(vias not_allowed)
				(pads allowed)
				(copperpour not_allowed)
				(footprints allowed)
			)
			(placement
				(enabled no)
				(sheetname "")
			)
			(fill
				(thermal_gap 0.5)
				(thermal_bridge_width 0.5)
				(island_removal_mode 0)
			)
			(polygon
				(pts
					(xy 341.4522 -87.7062) (xy 341.4522 -87.1982) (xy 341.8332 -87.1982) (xy 341.8332 -87.7062)
				)
			)
		)
		(zone
			(layer "B.Cu")
			(hatch none 0.5)
			(connect_pads
				(clearance 0)
			)
			(min_thickness 0.25)
			(keepout
				(tracks not_allowed)
				(vias allowed)
				(pads allowed)
				(copperpour not_allowed)
				(footprints allowed)
			)
			(placement
				(enabled no)
				(sheetname "")
			)
			(fill
				(thermal_gap 0.5)
				(thermal_bridge_width 0.5)
				(island_removal_mode 0)
			)
			(polygon
				(pts
					(xy 341.8332 -87.7062) (xy 341.8332 -87.1982) (xy 341.4522 -87.1982) (xy 341.4522 -87.7062)
				)
			)
		)
	)
	(footprint ""
		(layer "B.Cu")
		(at 420.624 -22.352)
		(property "Reference" "C25W75"
			(at 0.8382 -0.67818 0)
			(unlocked yes)
			(layer "B.SilkS")
			(effects
				(font
					(size 0.4064 0.254)
					(thickness 0.1524)
				)
				(justify left mirror)
			)
		)
		(property "Value" ""
			(at 0 0 0)
			(layer "B.Fab")
			(effects
				(font
					(size 1.27 1.27)
				)
				(justify mirror)
			)
		)
		(duplicate_pad_numbers_are_jumpers no)
		(fp_poly
			(pts
				(xy -0.3048 -0.1016) (xy -0.3048 0.9906) (xy 0.3048 0.9906) (xy 0.3048 -0.1016)
			)
			(stroke
				(width 0)
				(type default)
			)
			(fill no)
			(layer "B.CrtYd")
		)
		(fp_line
			(start -0.3048 -0.1016)
			(end 0.3048 -0.1016)
			(stroke
				(width 0.1)
				(type default)
			)
			(layer "B.Fab")
		)
		(fp_line
			(start -0.3048 0.9906)
			(end -0.3048 -0.1016)
			(stroke
				(width 0.1)
				(type default)
			)
			(layer "B.Fab")
		)
		(fp_line
			(start 0.3048 -0.1016)
			(end 0.3048 0.9906)
			(stroke
				(width 0.1)
				(type default)
			)
			(layer "B.Fab")
		)
		(fp_line
			(start 0.3048 0.9906)
			(end -0.3048 0.9906)
			(stroke
				(width 0.1)
				(type default)
			)
			(layer "B.Fab")
		)
		(pad "1" smd rect
			(at 0 0 180)
			(size 0.508 0.508)
			(layers "B.Cu" "B.Mask" "B.Paste")
			(net "V_IO_B_J")
		)
		(pad "2" smd rect
			(at 0 0.889 180)
			(size 0.508 0.508)
			(layers "B.Cu" "B.Mask" "B.Paste")
			(net "GND")
		)
		(zone
			(layer "B.Cu")
			(hatch none 0.5)
			(connect_pads
				(clearance 0)
			)
			(min_thickness 0.25)
			(keepout
				(tracks allowed)
				(vias not_allowed)
				(pads allowed)
				(copperpour not_allowed)
				(footprints allowed)
			)
			(placement
				(enabled no)
				(sheetname "")
			)
			(fill
				(thermal_gap 0.5)
				(thermal_bridge_width 0.5)
				(island_removal_mode 0)
			)
			(polygon
				(pts
					(xy 420.878 -22.098) (xy 420.37 -22.098) (xy 420.37 -21.717) (xy 420.878 -21.717)
				)
			)
		)
		(zone
			(layer "B.Cu")
			(hatch none 0.5)
			(connect_pads
				(clearance 0)
			)
			(min_thickness 0.25)
			(keepout
				(tracks not_allowed)
				(vias allowed)
				(pads allowed)
				(copperpour not_allowed)
				(footprints allowed)
			)
			(placement
				(enabled no)
				(sheetname "")
			)
			(fill
				(thermal_gap 0.5)
				(thermal_bridge_width 0.5)
				(island_removal_mode 0)
			)
			(polygon
				(pts
					(xy 420.878 -21.717) (xy 420.37 -21.717) (xy 420.37 -22.098) (xy 420.878 -22.098)
				)
			)
		)
	)
	(footprint ""
		(layer "B.Cu")
		(at 13.923264 2.985516 90)
		(property "Reference" "R9U7"
			(at 0 0 90)
			(layer "B.SilkS")
			(hide yes)
			(effects
				(font
					(size 1.27 1.27)
				)
				(justify mirror)
			)
		)
		(property "Value" ""
			(at 0 0 90)
			(layer "B.Fab")
			(effects
				(font
					(size 1.27 1.27)
				)
				(justify mirror)
			)
		)
		(duplicate_pad_numbers_are_jumpers no)
		(fp_poly
			(pts
				(xy 0.2794 -0.1016) (xy -0.2794 -0.1016) (xy -0.2794 0.9906) (xy 0.2794 0.9906)
			)
			(stroke
				(width 0)
				(type default)
			)
			(fill no)
			(layer "B.CrtYd")
		)
		(fp_line
			(start 0.2794 -0.1016)
			(end 0.2794 0.9906)
			(stroke
				(width 0.1)
				(type default)
			)
			(layer "B.Fab")
		)
		(fp_line
			(start -0.2794 -0.1016)
			(end 0.2794 -0.1016)
			(stroke
				(width 0.1)
				(type default)
			)
			(layer "B.Fab")
		)
		(fp_line
			(start 0.2794 0.9906)
			(end -0.2794 0.9906)
			(stroke
				(width 0.1)
				(type default)
			)
			(layer "B.Fab")
		)
		(fp_line
			(start -0.2794 0.9906)
			(end -0.2794 -0.1016)
			(stroke
				(width 0.1)
				(type default)
			)
			(layer "B.Fab")
		)
		(pad "1" smd rect
			(at 0 0 270)
			(size 0.508 0.508)
			(layers "B.Cu" "B.Mask" "B.Paste")
			(net "FM_PVDDQ_GHJ_EN")
		)
		(pad "2" smd rect
			(at 0 0.889 270)
			(size 0.508 0.508)
			(layers "B.Cu" "B.Mask" "B.Paste")
			(net "VR_PVDDQ_GHJ_VREN")
		)
		(zone
			(layer "B.Cu")
			(hatch none 0.5)
			(connect_pads
				(clearance 0)
			)
			(min_thickness 0.25)
			(keepout
				(tracks allowed)
				(vias not_allowed)
				(pads allowed)
				(copperpour not_allowed)
				(footprints allowed)
			)
			(placement
				(enabled no)
				(sheetname "")
			)
			(fill
				(thermal_gap 0.5)
				(thermal_bridge_width 0.5)
				(island_removal_mode 0)
			)
			(polygon
				(pts
					(xy 14.177264 2.731516) (xy 14.177264 3.239516) (xy 14.558264 3.239516) (xy 14.558264 2.731516)
				)
			)
		)
		(zone
			(layer "B.Cu")
			(hatch none 0.5)
			(connect_pads
				(clearance 0)
			)
			(min_thickness 0.25)
			(keepout
				(tracks not_allowed)
				(vias allowed)
				(pads allowed)
				(copperpour not_allowed)
				(footprints allowed)
			)
			(placement
				(enabled no)
				(sheetname "")
			)
			(fill
				(thermal_gap 0.5)
				(thermal_bridge_width 0.5)
				(island_removal_mode 0)
			)
			(polygon
				(pts
					(xy 14.558264 2.731516) (xy 14.558264 3.239516) (xy 14.177264 3.239516) (xy 14.177264 2.731516)
				)
			)
		)
	)
	(footprint ""
		(layer "B.Cu")
		(at 418.465 -4.191 90)
		(property "Reference" "CR7E1"
			(at 0 0 90)
			(layer "B.SilkS")
			(hide yes)
			(effects
				(font
					(size 1.27 1.27)
				)
				(justify mirror)
			)
		)
		(property "Value" ""
			(at 0 0 90)
			(layer "B.Fab")
			(effects
				(font
					(size 1.27 1.27)
				)
				(justify mirror)
			)
		)
		(duplicate_pad_numbers_are_jumpers no)
		(fp_line
			(start 1.335278 -0.291846)
			(end 1.335278 0.831596)
			(stroke
				(width 0.1524)
				(type default)
			)
			(layer "B.SilkS")
		)
		(fp_line
			(start 1.335278 0.831596)
			(end 0.854456 1.664462)
			(stroke
				(width 0.1524)
				(type default)
			)
			(layer "B.SilkS")
		)
		(fp_line
			(start 0.854456 0.831596)
			(end 1.8161 0.831596)
			(stroke
				(width 0.1524)
				(type default)
			)
			(layer "B.SilkS")
		)
		(fp_line
			(start 1.8161 1.664462)
			(end 1.335278 0.831596)
			(stroke
				(width 0.1524)
				(type default)
			)
			(layer "B.SilkS")
		)
		(fp_line
			(start 1.335278 1.664462)
			(end 1.8161 1.664462)
			(stroke
				(width 0.1524)
				(type default)
			)
			(layer "B.SilkS")
		)
		(fp_line
			(start 0.854456 1.664462)
			(end 1.335278 1.664462)
			(stroke
				(width 0.1524)
				(type default)
			)
			(layer "B.SilkS")
		)
		(fp_line
			(start 1.335278 2.576068)
			(end 1.335278 1.664462)
			(stroke
				(width 0.1524)
				(type default)
			)
			(layer "B.SilkS")
		)
		(fp_poly
			(pts
				(xy 0.67437 0.24384) (xy 0.67437 2.04216) (xy -0.67437 2.04216) (xy -0.67437 0.24384)
			)
			(stroke
				(width 0)
				(type default)
			)
			(fill no)
			(layer "B.CrtYd")
		)
		(fp_line
			(start 0.67437 0.24384)
			(end 0.67437 2.04216)
			(stroke
				(width 0.1)
				(type default)
			)
			(layer "B.Fab")
		)
		(fp_line
			(start -0.67437 0.24384)
			(end 0.67437 0.24384)
			(stroke
				(width 0.1)
				(type default)
			)
			(layer "B.Fab")
		)
		(fp_line
			(start 1.335278 0.831596)
			(end 1.335278 -0.291846)
			(stroke
				(width 0.1)
				(type default)
			)
			(layer "B.Fab")
		)
		(fp_line
			(start 1.335278 0.831596)
			(end 0.854456 1.664462)
			(stroke
				(width 0.1)
				(type default)
			)
			(layer "B.Fab")
		)
		(fp_line
			(start 0.854456 0.831596)
			(end 1.8161 0.831596)
			(stroke
				(width 0.1)
				(type default)
			)
			(layer "B.Fab")
		)
		(fp_line
			(start 1.8161 1.664462)
			(end 1.335278 0.831596)
			(stroke
				(width 0.1)
				(type default)
			)
			(layer "B.Fab")
		)
		(fp_line
			(start 1.335278 1.664462)
			(end 1.335278 2.576068)
			(stroke
				(width 0.1)
				(type default)
			)
			(layer "B.Fab")
		)
		(fp_line
			(start 0.854456 1.664462)
			(end 1.8161 1.664462)
			(stroke
				(width 0.1)
				(type default)
			)
			(layer "B.Fab")
		)
		(fp_line
			(start 0.67437 2.04216)
			(end -0.67437 2.04216)
			(stroke
				(width 0.1)
				(type default)
			)
			(layer "B.Fab")
		)
		(fp_line
			(start -0.67437 2.04216)
			(end -0.67437 0.24384)
			(stroke
				(width 0.1)
				(type default)
			)
			(layer "B.Fab")
		)
		(pad "1" smd rect
			(at 0 0 270)
			(size 0.4064 1.016)
			(layers "B.Cu" "B.Mask" "B.Paste")
			(net "PWRGD_P3V3_STBY")
		)
		(pad "2" smd rect
			(at 0 2.286 270)
			(size 0.4064 1.016)
			(layers "B.Cu" "B.Mask" "B.Paste")
			(net "PWRGD_DSW_PWROK")
		)
	)
)
